FILE_TYPE = MULTI_PHYS_TABLE;

PART 'SN74LVC1G07DCKR'

{========================================================================================}
:VALUE             | PART_TYPE | MATERIAL | PART_NUMBER    = STANDARD    | LIFECYCLE      | PART_NUMBER   | JEDEC_TYPE | DESCRIPTION                        | MANUFTR | MANUF_PN          | RD_CMPLS_LVL | CMPLS_LVL | FROM_PJ     | CLASS | DIP_SMD | DATA                      | EE_CHECK_LIST | FP_ECN | PSL | CREATOR | STATUS | MSD | ESD_CDM | ESD_HBM | ESD_MM | PIN_LENGTH_SHORT_PIN | PIN_LENGTH_LONG_PIN | CREATEDAY  ;
{========================================================================================}
 'SN74LVC1G07DCKR' | 'SMLF'    | 'IC'     | 'AL1G0007016'(!) = ''               | ''               | 'AL1G0007016' |'SC70-5XB'| 'IC OTHER(5P)SN74LVC1G07DCKR(SOT)' | 'TIC'   | 'SN74LVC1G07DCKR' | 'EP(V1)'     | 'EP(V1)'  | 'S50-STEVE' | 'IC'  | ''      | 'TIC_SN74LVC1G07DCKR.pdf' | ''            | ''     | ''  | ''      | ''     | ''  | ''      | ''      | ''     | ''                   | ''                  | '20100429'
 'SN74LVC1G07DCKR' | 'SMLF'    | 'EMPTY'  | 'AL1G0007016'(!) = ''               | ''               | 'AL1G0007016' |'SC70-5XB'| 'IC OTHER(5P)SN74LVC1G07DCKR(SOT)' | 'TIC'   | 'SN74LVC1G07DCKR' | 'EP(V1)'     | 'EP(V1)'  | 'S50-STEVE' | 'IC'  | ''      | 'TIC_SN74LVC1G07DCKR.pdf' | ''            | ''     | ''  | ''      | ''     | ''  | ''      | ''      | ''     | ''                   | ''                  | '20100429'

END_PART

END.

